(kicad_pcb
	(version 20260206)
	(generator "pcbnew")
	(generator_version "10.0")
	(general
		(thickness 1.6)
		(legacy_teardrops no)
	)
	(paper "A4")
	(title_block
		(title "Bryce Canyon_F.DPB_16315-1-OCP.brd")
		(comment 1 "Bryce Canyon / footprints 1871-1878 of 2223")
	)
	(layers
		(0 "F.Cu" signal "TOP")
		(4 "In1.Cu" signal "L2GND")
		(6 "In2.Cu" signal "L3")
		(8 "In3.Cu" signal "L4GND")
		(10 "In4.Cu" signal "L5")
		(12 "In5.Cu" signal "L6VCC")
		(14 "In6.Cu" signal "L7VCC")
		(16 "In7.Cu" signal "L8")
		(18 "In8.Cu" signal "L9GND")
		(20 "In9.Cu" signal "L10")
		(22 "In10.Cu" signal "L11GND")
		(2 "B.Cu" signal "BOTTOM")
		(9 "F.Adhes" user "F.Adhesive")
		(11 "B.Adhes" user "B.Adhesive")
		(13 "F.Paste" user "Package Geometry/Pastemask Top")
		(15 "B.Paste" user "Package Geometry/Pastemask Bottom")
		(5 "F.SilkS" user "Ref Des/Silkscreen Top")
		(7 "B.SilkS" user "Ref Des/Silkscreen Bottom")
		(1 "F.Mask" user "Board Geometry/Soldermask Top")
		(3 "B.Mask" user "Board Geometry/Soldermask Bottom")
		(17 "Dwgs.User" user "User.Drawings")
		(19 "Cmts.User" user "User.Comments")
		(21 "Eco1.User" user "User.Eco1")
		(23 "Eco2.User" user "User.Eco2")
		(25 "Edge.Cuts" user "Board Geometry/Outline")
		(27 "Margin" user)
		(31 "F.CrtYd" user "Package Geometry/Place Bound Top")
		(29 "B.CrtYd" user "Package Geometry/Place Bound Bottom")
		(35 "F.Fab" user "Ref Des/Assembly Top")
		(33 "B.Fab" user "Ref Des/Assembly Bottom")
	)
	(footprint ""
		(layer "F.Cu")
		(at 337.312 -277.792942 90)
		(property "Reference" "D6"
			(at 0 0 90)
			(layer "F.SilkS")
			(hide yes)
			(effects
				(font
					(size 1.27 1.27)
				)
			)
		)
		(property "Value" "RB551V30-GP"
			(at 0 -6.7818 90)
			(unlocked yes)
			(layer "F.Fab")
			(hide yes)
			(effects
				(font
					(size 1.016 1.016)
					(thickness 0.1524)
				)
			)
		)
		(property "Device Type" "SOD323AKH38"
			(at 0 -8.6868 90)
			(unlocked yes)
			(layer "F.Fab")
			(hide yes)
			(effects
				(font
					(size 1.016 1.016)
					(thickness 0.1524)
				)
			)
		)
		(duplicate_pad_numbers_are_jumpers no)
		(fp_line
			(start 0.889 -1.9304)
			(end 0.889 2.159)
			(stroke
				(width 0.1524)
				(type default)
			)
			(layer "F.SilkS")
		)
		(fp_line
			(start -0.889 -1.9304)
			(end 0.889 -1.9304)
			(stroke
				(width 0.1524)
				(type default)
			)
			(layer "F.SilkS")
		)
		(fp_line
			(start 0.762 2.0574)
			(end -0.762 2.0574)
			(stroke
				(width 0.508)
				(type default)
			)
			(layer "F.SilkS")
		)
		(fp_line
			(start 0.889 2.159)
			(end -0.889 2.159)
			(stroke
				(width 0.1524)
				(type default)
			)
			(layer "F.SilkS")
		)
		(fp_line
			(start -0.889 2.159)
			(end -0.889 -1.9304)
			(stroke
				(width 0.1524)
				(type default)
			)
			(layer "F.SilkS")
		)
		(fp_rect
			(start -1.016 2.3114)
			(end 1.016 -2.0066)
			(stroke
				(width 0)
				(type default)
			)
			(fill no)
			(layer "F.CrtYd")
		)
		(fp_poly
			(pts
				(xy -1.016 -2.0066) (xy 1.016 -2.0066) (xy 1.016 2.3114) (xy -1.016 2.3114)
			)
			(stroke
				(width 0)
				(type default)
			)
			(fill no)
			(layer "F.Fab")
		)
		(pad "A" smd rect
			(at 0 -1.143 90)
			(size 0.5588 1.016)
			(layers "F.Cu" "F.Mask" "F.Paste")
			(net "SW_HDD_R6")
		)
		(pad "K" smd rect
			(at 0 1.143 90)
			(size 0.5588 1.016)
			(layers "F.Cu" "F.Mask" "F.Paste")
			(net "SW_HDD_N6")
		)
	)
	(footprint ""
		(layer "F.Cu")
		(at 259.8674 -243.2685)
		(property "Reference" "R94"
			(at 0 0 0)
			(layer "F.SilkS")
			(hide yes)
			(effects
				(font
					(size 1.27 1.27)
				)
			)
		)
		(property "Value" "4K7R2F-GP"
			(at 0.064008 -3.993896 0)
			(unlocked yes)
			(layer "F.Fab")
			(hide yes)
			(effects
				(font
					(size 1.016 1.016)
					(thickness 0.1524)
				)
			)
		)
		(property "Device Type" "R402H16"
			(at 0.064008 -5.517896 0)
			(unlocked yes)
			(layer "F.Fab")
			(hide yes)
			(effects
				(font
					(size 1.016 1.016)
					(thickness 0.1524)
				)
			)
		)
		(duplicate_pad_numbers_are_jumpers no)
		(fp_line
			(start -0.508 -0.9398)
			(end -0.508 0.9398)
			(stroke
				(width 0.1524)
				(type default)
			)
			(layer "F.SilkS")
		)
		(fp_line
			(start 0.508 -0.9398)
			(end -0.508 -0.9398)
			(stroke
				(width 0.1524)
				(type default)
			)
			(layer "F.SilkS")
		)
		(fp_rect
			(start -0.508 0.9398)
			(end 0.508 -0.9398)
			(stroke
				(width 0)
				(type default)
			)
			(fill no)
			(layer "F.CrtYd")
		)
		(fp_rect
			(start -0.508 0.9398)
			(end 0.508 -0.9398)
			(stroke
				(width 0)
				(type default)
			)
			(fill no)
			(layer "F.Fab")
		)
		(pad "1" smd custom
			(at 0 -0.4445)
			(size 0.1397 0.1397)
			(layers "F.Cu" "F.Mask" "F.Paste")
			(net "P3V3_STBY_A")
			(options
				(clearance outline)
				(anchor circle)
			)
			(primitives
				(gr_poly
					(pts
						(arc
							(start -0.1778 -0.2794)
							(mid -0.249642 -0.249642)
							(end -0.2794 -0.1778)
						)
						(arc
							(start -0.2794 0.1778)
							(mid -0.249642 0.249642)
							(end -0.1778 0.2794)
						)
						(arc
							(start 0.1778 0.2794)
							(mid 0.249642 0.249642)
							(end 0.2794 0.1778)
						)
						(arc
							(start 0.2794 -0.1778)
							(mid 0.249642 -0.249642)
							(end 0.1778 -0.2794)
						)
					)
					(width 0)
					(fill yes)
				)
			)
		)
		(pad "2" smd custom
			(at 0 0.4445)
			(size 0.1397 0.1397)
			(layers "F.Cu" "F.Mask" "F.Paste")
			(net "IO_EXP3_INT_N")
			(options
				(clearance outline)
				(anchor circle)
			)
			(primitives
				(gr_poly
					(pts
						(arc
							(start -0.1778 -0.2794)
							(mid -0.249642 -0.249642)
							(end -0.2794 -0.1778)
						)
						(arc
							(start -0.2794 0.1778)
							(mid -0.249642 0.249642)
							(end -0.1778 0.2794)
						)
						(arc
							(start 0.1778 0.2794)
							(mid 0.249642 0.249642)
							(end 0.2794 0.1778)
						)
						(arc
							(start 0.2794 -0.1778)
							(mid 0.249642 -0.249642)
							(end 0.1778 -0.2794)
						)
					)
					(width 0)
					(fill yes)
				)
			)
		)
	)
	(footprint ""
		(layer "F.Cu")
		(at 376.4534 -134.8486 90)
		(property "Reference" "R1082"
			(at 0 0 90)
			(layer "F.SilkS")
			(hide yes)
			(effects
				(font
					(size 1.27 1.27)
				)
			)
		)
		(property "Value" "0R2J-2-GP"
			(at 0.064008 -3.993896 90)
			(unlocked yes)
			(layer "F.Fab")
			(hide yes)
			(effects
				(font
					(size 1.016 1.016)
					(thickness 0.1524)
				)
			)
		)
		(property "Device Type" "R402H16"
			(at 0.064008 -5.517896 90)
			(unlocked yes)
			(layer "F.Fab")
			(hide yes)
			(effects
				(font
					(size 1.016 1.016)
					(thickness 0.1524)
				)
			)
		)
		(duplicate_pad_numbers_are_jumpers no)
		(fp_line
			(start 0.508 -0.9398)
			(end -0.508 -0.9398)
			(stroke
				(width 0.1524)
				(type default)
			)
			(layer "F.SilkS")
		)
		(fp_line
			(start -0.508 -0.9398)
			(end -0.508 0.9398)
			(stroke
				(width 0.1524)
				(type default)
			)
			(layer "F.SilkS")
		)
		(fp_rect
			(start -0.508 0.9398)
			(end 0.508 -0.9398)
			(stroke
				(width 0)
				(type default)
			)
			(fill no)
			(layer "F.CrtYd")
		)
		(fp_rect
			(start -0.508 0.9398)
			(end 0.508 -0.9398)
			(stroke
				(width 0)
				(type default)
			)
			(fill no)
			(layer "F.Fab")
		)
		(pad "1" smd custom
			(at 0 -0.4445 90)
			(size 0.1397 0.1397)
			(layers "F.Cu" "F.Mask" "F.Paste")
			(net "MB1_SPISS_PD")
			(options
				(clearance outline)
				(anchor circle)
			)
			(primitives
				(gr_poly
					(pts
						(arc
							(start -0.1778 -0.2794)
							(mid -0.249642 -0.249642)
							(end -0.2794 -0.1778)
						)
						(arc
							(start -0.2794 0.1778)
							(mid -0.249642 0.249642)
							(end -0.1778 0.2794)
						)
						(arc
							(start 0.1778 0.2794)
							(mid 0.249642 0.249642)
							(end 0.2794 0.1778)
						)
						(arc
							(start 0.2794 -0.1778)
							(mid 0.249642 -0.249642)
							(end 0.1778 -0.2794)
						)
					)
					(width 0)
					(fill yes)
				)
			)
		)
		(pad "2" smd custom
			(at 0 0.4445 90)
			(size 0.1397 0.1397)
			(layers "F.Cu" "F.Mask" "F.Paste")
			(net "AGND_CURRENT_MONOB")
			(options
				(clearance outline)
				(anchor circle)
			)
			(primitives
				(gr_poly
					(pts
						(arc
							(start -0.1778 -0.2794)
							(mid -0.249642 -0.249642)
							(end -0.2794 -0.1778)
						)
						(arc
							(start -0.2794 0.1778)
							(mid -0.249642 0.249642)
							(end -0.1778 0.2794)
						)
						(arc
							(start 0.1778 0.2794)
							(mid 0.249642 0.249642)
							(end 0.2794 0.1778)
						)
						(arc
							(start 0.2794 -0.1778)
							(mid 0.249642 -0.249642)
							(end 0.1778 -0.2794)
						)
					)
					(width 0)
					(fill yes)
				)
			)
		)
	)
	(footprint ""
		(layer "F.Cu")
		(at 317.627 -69.469)
		(property "Reference" "TP152"
			(at 0 0 0)
			(layer "F.SilkS")
			(hide yes)
			(effects
				(font
					(size 1.27 1.27)
				)
			)
		)
		(property "Value" "TPAD32-GP"
			(at -0.0508 -1.6764 0)
			(unlocked yes)
			(layer "F.Fab")
			(hide yes)
			(effects
				(font
					(size 1.016 1.016)
					(thickness 0.1524)
				)
			)
		)
		(property "Device Type" "TPAD32"
			(at -0.0508 -3.2004 0)
			(unlocked yes)
			(layer "F.Fab")
			(hide yes)
			(effects
				(font
					(size 1.016 1.016)
					(thickness 0.1524)
				)
			)
		)
		(duplicate_pad_numbers_are_jumpers no)
		(fp_poly
			(pts
				(arc
					(start 0.4064 0)
					(mid -0.4064 0)
					(end 0.4064 0)
				)
			)
			(stroke
				(width 0)
				(type default)
			)
			(fill no)
			(layer "F.CrtYd")
		)
		(fp_poly
			(pts
				(arc
					(start 0.7112 0)
					(mid -0.7112 0)
					(end 0.7112 0)
				)
			)
			(stroke
				(width 0)
				(type default)
			)
			(fill no)
			(layer "F.Fab")
		)
		(pad "1" smd circle
			(at 0 0)
			(size 0.8128 0.8128)
			(layers "F.Cu" "F.Mask" "F.Paste")
			(net "ACT_HDD_30")
		)
	)
	(footprint ""
		(layer "F.Cu")
		(at 22.996398 -163.554918 90)
		(property "Reference" "R419"
			(at 0 0 90)
			(layer "F.SilkS")
			(hide yes)
			(effects
				(font
					(size 1.27 1.27)
				)
			)
		)
		(property "Value" "4K7R2J-2-GP"
			(at 0.064008 -3.993896 90)
			(unlocked yes)
			(layer "F.Fab")
			(hide yes)
			(effects
				(font
					(size 1.016 1.016)
					(thickness 0.1524)
				)
			)
		)
		(property "Device Type" "R402H16"
			(at 0.064008 -5.517896 90)
			(unlocked yes)
			(layer "F.Fab")
			(hide yes)
			(effects
				(font
					(size 1.016 1.016)
					(thickness 0.1524)
				)
			)
		)
		(duplicate_pad_numbers_are_jumpers no)
		(fp_line
			(start 0.508 -0.9398)
			(end -0.508 -0.9398)
			(stroke
				(width 0.1524)
				(type default)
			)
			(layer "F.SilkS")
		)
		(fp_line
			(start -0.508 -0.9398)
			(end -0.508 0.9398)
			(stroke
				(width 0.1524)
				(type default)
			)
			(layer "F.SilkS")
		)
		(fp_rect
			(start -0.508 0.9398)
			(end 0.508 -0.9398)
			(stroke
				(width 0)
				(type default)
			)
			(fill no)
			(layer "F.CrtYd")
		)
		(fp_rect
			(start -0.508 0.9398)
			(end 0.508 -0.9398)
			(stroke
				(width 0)
				(type default)
			)
			(fill no)
			(layer "F.Fab")
		)
		(pad "1" smd custom
			(at 0 -0.4445 90)
			(size 0.1397 0.1397)
			(layers "F.Cu" "F.Mask" "F.Paste")
			(net "SW_PWR_R_HDD12")
			(options
				(clearance outline)
				(anchor circle)
			)
			(primitives
				(gr_poly
					(pts
						(arc
							(start -0.1778 -0.2794)
							(mid -0.249642 -0.249642)
							(end -0.2794 -0.1778)
						)
						(arc
							(start -0.2794 0.1778)
							(mid -0.249642 0.249642)
							(end -0.1778 0.2794)
						)
						(arc
							(start 0.1778 0.2794)
							(mid 0.249642 0.249642)
							(end 0.2794 0.1778)
						)
						(arc
							(start 0.2794 -0.1778)
							(mid 0.249642 -0.249642)
							(end 0.1778 -0.2794)
						)
					)
					(width 0)
					(fill yes)
				)
			)
		)
		(pad "2" smd custom
			(at 0 0.4445 90)
			(size 0.1397 0.1397)
			(layers "F.Cu" "F.Mask" "F.Paste")
			(net "GND")
			(options
				(clearance outline)
				(anchor circle)
			)
			(primitives
				(gr_poly
					(pts
						(arc
							(start -0.1778 -0.2794)
							(mid -0.249642 -0.249642)
							(end -0.2794 -0.1778)
						)
						(arc
							(start -0.2794 0.1778)
							(mid -0.249642 0.249642)
							(end -0.1778 0.2794)
						)
						(arc
							(start 0.1778 0.2794)
							(mid 0.249642 0.249642)
							(end 0.2794 0.1778)
						)
						(arc
							(start 0.2794 -0.1778)
							(mid 0.249642 -0.249642)
							(end 0.1778 -0.2794)
						)
					)
					(width 0)
					(fill yes)
				)
			)
		)
	)
	(footprint ""
		(layer "F.Cu")
		(at 346.700094 -94.400116)
		(property "Reference" "FLED20"
			(at 0 0 0)
			(layer "F.SilkS")
			(hide yes)
			(effects
				(font
					(size 1.27 1.27)
				)
			)
		)
		(property "Value" "LED-BY-19-GP"
			(at -2.132076 1.414018 0)
			(unlocked yes)
			(layer "F.Fab")
			(hide yes)
			(effects
				(font
					(size 1.016 1.016)
					(thickness 0.1524)
				)
			)
		)
		(property "Device Type" "LED-1615-4PH26"
			(at -2.132076 -0.109982 0)
			(unlocked yes)
			(layer "F.Fab")
			(hide yes)
			(effects
				(font
					(size 1.016 1.016)
					(thickness 0.1524)
				)
			)
		)
		(duplicate_pad_numbers_are_jumpers no)
		(fp_line
			(start -1.2954 0.254)
			(end -1.2954 1.6002)
			(stroke
				(width 0.508)
				(type default)
			)
			(layer "F.SilkS")
		)
		(fp_line
			(start -1.2954 1.6002)
			(end 1.2954 1.6002)
			(stroke
				(width 0.508)
				(type default)
			)
			(layer "F.SilkS")
		)
		(fp_line
			(start -1.1176 -1.4224)
			(end 1.1176 -1.4224)
			(stroke
				(width 0.1524)
				(type default)
			)
			(layer "F.SilkS")
		)
		(fp_line
			(start -1.1176 1.4224)
			(end -1.1176 -1.4224)
			(stroke
				(width 0.1524)
				(type default)
			)
			(layer "F.SilkS")
		)
		(fp_line
			(start 1.1176 -1.4224)
			(end 1.1176 1.4224)
			(stroke
				(width 0.1524)
				(type default)
			)
			(layer "F.SilkS")
		)
		(fp_line
			(start 1.1176 1.4224)
			(end -1.1176 1.4224)
			(stroke
				(width 0.1524)
				(type default)
			)
			(layer "F.SilkS")
		)
		(fp_line
			(start 1.2954 1.6002)
			(end 1.2954 0.254)
			(stroke
				(width 0.508)
				(type default)
			)
			(layer "F.SilkS")
		)
		(fp_rect
			(start -0.7493 0.8001)
			(end 0.7493 -0.8001)
			(stroke
				(width 0)
				(type default)
			)
			(fill no)
			(layer "F.CrtYd")
		)
		(fp_poly
			(pts
				(xy -1.3716 1.6764) (xy -1.3716 -1.6764) (xy 1.3716 -1.6764) (xy 1.3716 0.0635) (xy 0.7493 0.0635)
				(xy 0.7493 -0.8001) (xy -0.7493 -0.8001) (xy -0.7493 0.8001) (xy 0.7493 0.8001) (xy 0.7493 0.0762)
				(xy 1.3716 0.0762) (xy 1.3716 1.6764)
			)
			(stroke
				(width 0)
				(type default)
			)
			(fill no)
			(layer "F.CrtYd")
		)
		(fp_rect
			(start -1.3716 1.6764)
			(end 1.3716 -1.6764)
			(stroke
				(width 0)
				(type default)
			)
			(fill no)
			(layer "F.Fab")
		)
		(pad "1" smd rect
			(at 0.50038 -0.73025)
			(size 0.7112 0.8636)
			(layers "F.Cu" "F.Mask" "F.Paste")
			(net "DRV_ACT_19")
		)
		(pad "2" smd rect
			(at -0.50038 -0.73025)
			(size 0.7112 0.8636)
			(layers "F.Cu" "F.Mask" "F.Paste")
			(net "FLT_HDD19")
		)
		(pad "3" smd rect
			(at 0.50038 0.73025)
			(size 0.7112 0.8636)
			(layers "F.Cu" "F.Mask" "F.Paste")
			(net "DRV_ACT_19_N")
		)
		(pad "4" smd rect
			(at -0.50038 0.73025)
			(size 0.7112 0.8636)
			(layers "F.Cu" "F.Mask" "F.Paste")
			(net "FLT_HDD19_N")
		)
	)
	(footprint ""
		(layer "F.Cu")
		(at 387.83895 -47.749968 -90)
		(property "Reference" "VIA32"
			(at 0 0 270)
			(layer "F.SilkS")
			(hide yes)
			(effects
				(font
					(size 1.27 1.27)
				)
			)
		)
		(property "Value" "100OHM-8L-1D6MM-L18L16-GP"
			(at -3.7211 -4.5085 270)
			(unlocked yes)
			(layer "F.Fab")
			(hide yes)
			(effects
				(font
					(size 1.016 1.016)
					(thickness 0.1524)
				)
			)
		)
		(property "Device Type" "VIA-PCIE-4P-394076"
			(at -3.7211 -6.0325 270)
			(unlocked yes)
			(layer "F.Fab")
			(hide yes)
			(effects
				(font
					(size 1.016 1.016)
					(thickness 0.1524)
				)
			)
		)
		(duplicate_pad_numbers_are_jumpers no)
		(fp_rect
			(start -1.9685 0.381)
			(end 1.9685 -0.381)
			(stroke
				(width 0)
				(type default)
			)
			(fill no)
			(layer "F.CrtYd")
		)
		(fp_rect
			(start -1.9685 0.381)
			(end 1.9685 -0.381)
			(stroke
				(width 0)
				(type default)
			)
			(fill no)
			(layer "F.Fab")
		)
		(pad "1" thru_hole circle
			(at -1.5875 0 270)
			(size 0.508 0.508)
			(drill 0.254)
			(layers "*.Cu" "*.Mask")
			(remove_unused_layers no)
			(net "GND")
			(clearance 0.127)
			(thermal_gap 0.127)
		)
		(pad "2" thru_hole circle
			(at -0.5715 0 270)
			(size 0.508 0.508)
			(drill 0.254)
			(layers "*.Cu" "*.Mask")
			(remove_unused_layers no)
			(net "PHY_DRV_A_TO_SCC_A_32_DP")
			(clearance 0.127)
			(thermal_gap 0.127)
		)
		(pad "3" thru_hole circle
			(at 0.5715 0 270)
			(size 0.508 0.508)
			(drill 0.254)
			(layers "*.Cu" "*.Mask")
			(remove_unused_layers no)
			(net "PHY_DRV_A_TO_SCC_A_32_DN")
			(clearance 0.127)
			(thermal_gap 0.127)
		)
		(pad "4" thru_hole circle
			(at 1.5875 0 270)
			(size 0.508 0.508)
			(drill 0.254)
			(layers "*.Cu" "*.Mask")
			(remove_unused_layers no)
			(net "GND")
			(clearance 0.127)
			(thermal_gap 0.127)
		)
	)
	(footprint ""
		(layer "F.Cu")
		(at 46.392846 -54.523894 90)
		(property "Reference" "C374"
			(at 0 0 90)
			(layer "F.SilkS")
			(hide yes)
			(effects
				(font
					(size 1.27 1.27)
				)
			)
		)
		(property "Value" "SCD033U25V2KX-GP"
			(at 1.1811 -2.7051 90)
			(unlocked yes)
			(layer "F.Fab")
			(hide yes)
			(effects
				(font
					(size 1.016 1.016)
					(thickness 0.1524)
				)
			)
		)
		(property "Device Type" "C402H22"
			(at 1.1811 -4.2291 90)
			(unlocked yes)
			(layer "F.Fab")
			(hide yes)
			(effects
				(font
					(size 1.016 1.016)
					(thickness 0.1524)
				)
			)
		)
		(duplicate_pad_numbers_are_jumpers no)
		(fp_rect
			(start -0.4318 0.9525)
			(end 0.4318 -0.9525)
			(stroke
				(width 0)
				(type default)
			)
			(fill no)
			(layer "F.CrtYd")
		)
		(fp_rect
			(start -0.4318 0.9525)
			(end 0.4318 -0.9525)
			(stroke
				(width 0)
				(type default)
			)
			(fill no)
			(layer "F.Fab")
		)
		(pad "1" smd custom
			(at 0 -0.4445 90)
			(size 0.1524 0.1524)
			(layers "F.Cu" "F.Mask" "F.Paste")
			(net "P12V_A")
			(options
				(clearance outline)
				(anchor circle)
			)
			(primitives
				(gr_poly
					(pts
						(arc
							(start 0.3048 -0.2032)
							(mid 0.275042 -0.275042)
							(end 0.2032 -0.3048)
						)
						(arc
							(start -0.2032 -0.3048)
							(mid -0.275042 -0.275042)
							(end -0.3048 -0.2032)
						)
						(arc
							(start -0.3048 0.2032)
							(mid -0.275042 0.275042)
							(end -0.2032 0.3048)
						)
						(arc
							(start 0.2032 0.3048)
							(mid 0.275042 0.275042)
							(end 0.3048 0.2032)
						)
					)
					(width 0)
					(fill yes)
				)
			)
		)
		(pad "2" smd custom
			(at 0 0.4445 90)
			(size 0.1524 0.1524)
			(layers "F.Cu" "F.Mask" "F.Paste")
			(net "SW_HDD_N25")
			(options
				(clearance outline)
				(anchor circle)
			)
			(primitives
				(gr_poly
					(pts
						(arc
							(start 0.3048 -0.2032)
							(mid 0.275042 -0.275042)
							(end 0.2032 -0.3048)
						)
						(arc
							(start -0.2032 -0.3048)
							(mid -0.275042 -0.275042)
							(end -0.3048 -0.2032)
						)
						(arc
							(start -0.3048 0.2032)
							(mid -0.275042 0.275042)
							(end -0.2032 0.3048)
						)
						(arc
							(start 0.2032 0.3048)
							(mid 0.275042 0.275042)
							(end 0.3048 0.2032)
						)
					)
					(width 0)
					(fill yes)
				)
			)
		)
	)
)
